FILE_TYPE = CONNECTIVITY;
{Allegro Design Entry HDL 16.6-p007 (v16-6-112F) 10/10/2012}
"PAGE_NUMBER" = 38;
0"NC";
1"PVDDQ_ABC\g";
2"PVDDQ_DEF\g";
3"PVCCIO_CPU0\g";
4"GND\g";
5"PVCCIO_CPU0\g";
6"PVSA_CPU0\g";
7"PVCCIOMCP_CPU0\g";
8"PVCCMCP_CPU0\g";
9"PVPP_ABC\g";
10"P1V8_MCP_CPU0\g";
11"P3V3_STBY\g";
%"PVDDQ_ABC"
"1","(-3075,4400)","0","mstr_symbols","I11";
;
VOLTAGE"1.2V"
CDS_LIB"mstr_symbols"
BODY_TYPE"PLUMBING"
HDL_POWER"PVDDQ_ABC";
"G\NAC"1;
%"PVDDQ_DEF"
"1","(-800,4400)","0","mstr_symbols","I12";
;
VOLTAGE"1.2V"
CDS_LIB"mstr_symbols"
BODY_TYPE"PLUMBING"
HDL_POWER"PVDDQ_DEF";
"G\NAC"2;
%"PVCCIO_CPU0"
"1","(-250,4875)","0","mstr_symbols","I14";
;
VOLTAGE"1.1V"
CDS_LIB"mstr_symbols"
BODY_TYPE"PLUMBING"
HDL_POWER"PVCCIO_CPU0";
"G\NAC"3;
%"GND"
"1","(3000,1175)","0","mstr_symbols","I16";
;
HDL_POWER"GND"
BODY_TYPE"PLUMBING"
SIZE"1B"
CDS_LIB"mstr_symbols"
VOLTAGE"0.0V";
"A\NAC"4;
%"PVCCIO_CPU0"
"1","(2450,1175)","0","mstr_symbols","I17";
;
VOLTAGE"1.1V"
CDS_LIB"mstr_symbols"
BODY_TYPE"PLUMBING"
HDL_POWER"PVCCIO_CPU0";
"G\NAC"5;
%"CAP"
"1","(3000,1350)","0","mstr_discrete","I19";
;
CDS_SEC"1"
GROUP"PWR_MCP_CAP"
MATERIAL"X6S"
VOLTAGE"4V"
PACK_TYPE"0603LF"
TOLERANCE"20%"
VALUE"10UF"
PART_NUMBER"E15431-001"
LOCATION"C6D1"
ROOM"CPU0"
CDS_LOCATION"C6D1"
SEC"1"
BOM_COST"PROC_SOCKET"
SEC_TYPE"0603LF"
CDS_LIB"mstr_discrete";
"A"
$PN"1"10;
"B"
$PN"2"4;
%"PVSA_CPU0"
"1","(2150,4950)","0","mstr_symbols","I24";
;
VOLTAGE"1.1V"
CDS_LIB"mstr_symbols"
BODY_TYPE"PLUMBING"
HDL_POWER"PVSA_CPU0";
"G\NAC"6;
%"VCC_CORE"
"1","(2500,2725)","0","mstr_symbols","I25";
;
HDL_POWER"PVCCIOMCP_CPU0"
CDS_LIB"mstr_symbols";
"A"7;
%"VCC_CORE"
"1","(2500,3450)","0","mstr_symbols","I26";
;
HDL_POWER"PVCCMCP_CPU0"
CDS_LIB"mstr_symbols";
"A"8;
%"PVPP_ABC"
"1","(2325,2025)","0","mstr_symbols","I31";
;
VOLTAGE"2.5V"
CDS_LIB"mstr_symbols"
BOM_COST"PVPP_KLM_VR"
BODY_TYPE"PLUMBING"
ROOM"PVPP_KLM_VR"
HDL_POWER"PVPP_ABC";
"G\NAC"9;
%"SKX_EXT_B"
"20","(-1950,2650)","0","chpset_lib","I33";
;
CDS_SEC"20"
PART_NUMBER"TBD"
MATERIAL"IC"
LOCATION"U5D1"
PACK_TYPE"BGA1"
SEC_TYPE"BGA1"
CDS_LIB"chpset_lib"
SEC"20"
CDS_LOCATION"U5D1"
ROOM"CPU0";
"VCCD345<0>"
$PN"EF59"2;
"VCCD345<1>"
$PN"EF53"2;
"VCCD345<2>"
$PN"EF49"2;
"VCCD345<3>"
$PN"EC62"2;
"VCCD345<4>"
$PN"EC60"2;
"VCCD345<5>"
$PN"EC58"2;
"VCCD345<6>"
$PN"EC56"2;
"VCCD345<7>"
$PN"EC54"2;
"VCCD345<8>"
$PN"EC52"2;
"VCCD345<9>"
$PN"EC50"2;
"VCCD345<10>"
$PN"EC48"2;
"VCCD345<11>"
$PN"EC46"2;
"VCCD345<12>"
$PN"DU64"2;
"VCCD345<13>"
$PN"DU62"2;
"VCCD345<14>"
$PN"DU60"2;
"VCCD345<15>"
$PN"DU58"2;
"VCCD345<16>"
$PN"DU56"2;
"VCCD345<17>"
$PN"DU54"2;
"VCCD345<18>"
$PN"DU52"2;
"VCCD345<19>"
$PN"DU50"2;
"VCCD345<20>"
$PN"DU48"2;
"VCCD345<21>"
$PN"DU46"2;
"VCCD345<22>"
$PN"DL62"2;
"VCCD345<23>"
$PN"DL60"2;
"VCCD345<24>"
$PN"DL58"2;
"VCCD345<25>"
$PN"DL56"2;
"VCCD345<26>"
$PN"DL54"2;
"VCCD345<27>"
$PN"DL52"2;
"VCCD345<28>"
$PN"DL50"2;
"VCCD345<29>"
$PN"DL48"2;
"VCCD345<30>"
$PN"DL46"2;
"VCCD345<31>"
$PN"DJ64"2;
"VCCD345<32>"
$PN"DH63"2;
"VCCD345<33>"
$PN"DH61"2;
"VCCD345<34>"
$PN"DH59"2;
"VCCD345<35>"
$PN"DH57"2;
"VCCD345<36>"
$PN"DH55"2;
"VCCD345<37>"
$PN"DH53"2;
"VCCD345<38>"
$PN"DH51"2;
"VCCD345<39>"
$PN"DH49"2;
"VCCD345<40>"
$PN"DH47"2;
"VCCD345<41>"
$PN"DH45"2;
"VCCD345<42>"
$PN"DD45"2;
"VCCD345<43>"
$PN"DB63"2;
"VCCD345<44>"
$PN"DB61"2;
"VCCD345<45>"
$PN"DB59"2;
"VCCD345<46>"
$PN"DB57"2;
"VCCD345<47>"
$PN"DB55"2;
"VCCD345<48>"
$PN"DB53"2;
"VCCD345<49>"
$PN"EF45"2;
"VCCD345<50>"
$PN"EE44"2;
"VCCD012<0>"
$PN"B49"1;
"VCCD012<1>"
$PN"B53"1;
"VCCD012<2>"
$PN"B59"1;
"VCCD012<3>"
$PN"E46"1;
"VCCD012<4>"
$PN"E48"1;
"VCCD012<5>"
$PN"E50"1;
"VCCD012<6>"
$PN"E52"1;
"VCCD012<7>"
$PN"E54"1;
"VCCD012<8>"
$PN"E56"1;
"VCCD012<9>"
$PN"E58"1;
"VCCD012<10>"
$PN"E60"1;
"VCCD012<11>"
$PN"E62"1;
"VCCD012<12>"
$PN"E64"1;
"VCCD012<13>"
$PN"L46"1;
"VCCD012<14>"
$PN"L48"1;
"VCCD012<15>"
$PN"L50"1;
"VCCD012<16>"
$PN"L52"1;
"VCCD012<17>"
$PN"L54"1;
"VCCD012<18>"
$PN"L56"1;
"VCCD012<19>"
$PN"L58"1;
"VCCD012<20>"
$PN"L60"1;
"VCCD012<21>"
$PN"L62"1;
"VCCD012<22>"
$PN"N64"1;
"VCCD012<23>"
$PN"U46"1;
"VCCD012<24>"
$PN"U48"1;
"VCCD012<25>"
$PN"U50"1;
"VCCD012<26>"
$PN"U52"1;
"VCCD012<27>"
$PN"U54"1;
"VCCD012<28>"
$PN"U56"1;
"VCCD012<29>"
$PN"U58"1;
"VCCD012<30>"
$PN"U60"1;
"VCCD012<31>"
$PN"U62"1;
"VCCD012<32>"
$PN"W64"1;
"VCCD012<33>"
$PN"Y45"1;
"VCCD012<34>"
$PN"Y47"1;
"VCCD012<35>"
$PN"Y49"1;
"VCCD012<36>"
$PN"Y51"1;
"VCCD012<37>"
$PN"Y53"1;
"VCCD012<38>"
$PN"Y55"1;
"VCCD012<39>"
$PN"Y57"1;
"VCCD012<40>"
$PN"Y59"1;
"VCCD012<41>"
$PN"Y61"1;
"VCCD012<42>"
$PN"Y63"1;
"VCCD012<43>"
$PN"AD45"1;
"VCCD012<44>"
$PN"AF55"1;
"VCCD012<45>"
$PN"AF57"1;
"VCCD012<46>"
$PN"AF59"1;
"VCCD012<47>"
$PN"AF61"1;
"VCCD012<48>"
$PN"AF63"1;
"VCCD012<49>"
$PN"D45"1;
"VCCD012<50>"
$PN"C46"1;
"VCCD012<51>"
$PN"B47"1;
%"SKX_EXT_B"
"21","(1050,2725)","0","chpset_lib","I34";
;
CDS_SEC"21"
LOCATION"U5D1"
PART_NUMBER"TBD"
MATERIAL"IC"
PACK_TYPE"BGA1"
SEC_TYPE"BGA1"
CDS_LIB"chpset_lib"
SEC"21"
CDS_LOCATION"U5D1"
ROOM"CPU0";
"VCCSA<0>"
$PN"CJ66"6;
"VCCSA<1>"
$PN"CJ64"6;
"VCCSA<2>"
$PN"CH75"6;
"VCCSA<3>"
$PN"CH65"6;
"VCCSA<4>"
$PN"CG74"6;
"VCCSA<5>"
$PN"CG66"6;
"VCCSA<6>"
$PN"CG64"6;
"VCCSA<7>"
$PN"CF75"6;
"VCCSA<8>"
$PN"CF73"6;
"VCCSA<9>"
$PN"CF67"6;
"VCCSA<10>"
$PN"CF65"6;
"VCCSA<11>"
$PN"CE74"6;
"VCCSA<12>"
$PN"CE72"6;
"VCCSA<13>"
$PN"CE68"6;
"VCCSA<14>"
$PN"CE66"6;
"VCCSA<15>"
$PN"CE64"6;
"VCCSA<16>"
$PN"CD71"6;
"VCCSA<17>"
$PN"CD69"6;
"VCCSA<18>"
$PN"CD67"6;
"VCCSA<19>"
$PN"CD65"6;
"VCCSA<20>"
$PN"CC70"6;
"VCCSA<21>"
$PN"CC68"6;
"VCCSA<22>"
$PN"CC66"6;
"VCCSA<23>"
$PN"CB69"6;
"VCCSA<24>"
$PN"CB67"6;
"VCCSA<25>"
$PN"CB65"6;
"VCCIO<20>"
$PN"CM15"5;
"VCCIO<21>"
$PN"CL12"5;
"VCCIO<22>"
$PN"CK5"5;
"VCCIO<23>"
$PN"CV7"5;
"VCCIO<24>"
$PN"CH9"5;
"VCCIO<25>"
$PN"D7"5;
"VCCIO<26>"
$PN"CE18"5;
"VCCIO<27>"
$PN"CD9"5;
"VCCIO<28>"
$PN"CB17"5;
"VCCIO<29>"
$PN"CB13"5;
"VCCIO<30>"
$PN"BP25"3;
"VCCIO<31>"
$PN"BJ24"3;
"VCCIO<32>"
$PN"BF23"3;
"VCCIO<33>"
$PN"DA14"3;
"VCCIO<34>"
$PN"BB5"3;
"VCCIO<35>"
$PN"BA24"3;
"VCCIO<36>"
$PN"AY11"3;
"VCCIO<37>"
$PN"AW6"3;
"VCCIO<38>"
$PN"AT11"3;
"VCCIO<39>"
$PN"DD7"3;
"VCCIO<40>"
$PN"AN10"3;
"VCCIO<41>"
$PN"DF13"3;
"VCCIO<42>"
$PN"AH9"3;
"VCCIO<43>"
$PN"AC4"3;
"VCCIO<44>"
$PN"AC20"3;
"VCCIO<45>"
$PN"AA10"3;
"VCCIO<46>"
$PN"W6"3;
"VCCIO<47>"
$PN"W4"3;
"VCCIO<48>"
$PN"DF21"3;
"VCCIO<49>"
$PN"U14"3;
"VCCIO<50>"
$PN"T3"3;
"VCCIO<51>"
$PN"P5"3;
"VCCIO<52>"
$PN"M21"3;
"VCCIO<53>"
$PN"M11"3;
"VCCIO<54>"
$PN"DG8"3;
"VCCIO<55>"
$PN"DH7"3;
"VCCIO<56>"
$PN"L16"3;
"VCCIO<57>"
$PN"L14"3;
"VCCIO<58>"
$PN"J10"3;
"VCCIO<59>"
$PN"H13"3;
"VCCIO<60>"
$PN"DJ16"3;
"VCCIO<61>"
$PN"DM17"3;
"VCCIO<62>"
$PN"DN8"3;
"VCCIO<63>"
$PN"DP19"3;
"VCCIO<64>"
$PN"DR10"3;
"VCCIO<65>"
$PN"DR2"3;
"VCCIO<66>"
$PN"DU20"3;
"VCCIO<67>"
$PN"EA12"3;
"VCCIO<68>"
$PN"EB15"3;
"VCCIO<69>"
$PN"J2"3;
"VCCIO<70>"
$PN"K15"3;
"VCCIO<71>"
$PN"M7"3;
"VCCIO<72>"
$PN"M9"3;
"VCCIO<73>"
$PN"N18"3;
"VCCIO<74>"
$PN"W10"3;
"VCCIO<75>"
$PN"BC26"3;
"VCCIO<76>"
$PN"BB27"3;
"VCCIO<77>"
$PN"BA26"3;
"VCCIO<78>"
$PN"AY27"3;
"VCCIO<79>"
$PN"AW26"3;
"VCCIO<80>"
$PN"AV27"3;
"VCCIO<81>"
$PN"CF27"3;
"VCCIO<82>"
$PN"CD27"3;
"VCCIO<83>"
$PN"CC26"3;
"VCCIO<84>"
$PN"CJ28"3;
"VCCIO<85>"
$PN"CH27"3;
"VCCIO<86>"
$PN"BM27"3;
"VCCIO<87>"
$PN"BL26"3;
"VCCIO<88>"
$PN"BK27"3;
"VCCIO<89>"
$PN"BK25"3;
"VCCIO<90>"
$PN"BJ26"3;
"VCCIO<91>"
$PN"BH27"3;
"VCCIO<92>"
$PN"BH25"3;
"VCCIO<93>"
$PN"BG26"3;
"VCCIO<94>"
$PN"BF27"3;
"VCCIO<95>"
$PN"AE36"3;
"VCCIO<96>"
$PN"AD37"3;
"VCCIO<97>"
$PN"AC36"3;
"VCCIO<98>"
$PN"AF35"3;
"VCCIO<99>"
$PN"AD35"3;
"VCCIO<100>"
$PN"AE34"3;
"VCCIO<101>"
$PN"AG34"3;
"VCCIO<102>"
$PN"AM29"3;
"VCCIO<103>"
$PN"AL28"3;
"VCCIO<104>"
$PN"AR28"3;
"VCC33"
$PN"CY55"11;
"CD_VPP<0>"
$PN"B11"9;
"CD_VPP<1>"
$PN"A12"9;
"CD_VPP<2>"
$PN"A10"9;
"CD_VPP<3>"
$PN"A8"9;
"CD_VCC_CORE<0>"
$PN"BL14"8;
"CD_VCC_CORE<1>"
$PN"BK15"8;
"CD_VCC_CORE<2>"
$PN"BK13"8;
"CD_VCC_CORE<3>"
$PN"BJ14"8;
"CD_VCC_CORE<4>"
$PN"BJ12"8;
"CD_VCC_CORE<5>"
$PN"BH13"8;
"CD_VCC_CORE<6>"
$PN"BG14"8;
"CD_VCC_CORE<7>"
$PN"BG12"8;
"CD_VCC_CORE<8>"
$PN"BF13"8;
"CD_VCC_CORE<9>"
$PN"BF11"8;
"CD_VCC_CORE<10>"
$PN"BE14"8;
"CD_VCC_CORE<11>"
$PN"BE12"8;
"CD_VCC_CORE<12>"
$PN"BD13"8;
"CD_VCCP<0>"
$PN"BV15"7;
"CD_VCCP<1>"
$PN"BV13"7;
"CD_VCCP<2>"
$PN"BV11"7;
"CD_VCCP<3>"
$PN"BU14"7;
"CD_VCCP<4>"
$PN"BU12"7;
"CD_VCCP<5>"
$PN"BT15"7;
"CD_VCCP<6>"
$PN"BT13"7;
"CD_VCCP<7>"
$PN"BT11"7;
"CD_VCCP<8>"
$PN"BR14"7;
"CD_VCCP<9>"
$PN"BR12"7;
"CD_VCCP<10>"
$PN"BP15"7;
"CD_VCCP<11>"
$PN"BP13"7;
"CD_VCCP<12>"
$PN"BP11"7;
"CD_VCCP<13>"
$PN"BN14"7;
"CD_VCCP<14>"
$PN"BN12"7;
"CD_VCCP<15>"
$PN"BM11"7;
"CD_VCCIN<0>"
$PN"BT27"10;
"CD_VCCIN<1>"
$PN"BU26"10;
"CD_VCCIN<2>"
$PN"BV27"10;
"CD_VCCIN<3>"
$PN"BY27"10;
%"VCC_CORE"
"1","(3000,1600)","0","mstr_symbols","I35";
;
HDL_POWER"P1V8_MCP_CPU0"
CDS_LIB"mstr_symbols"
VOLTAGE"+1.8V";
"A"10;
%"P3V3_STBY"
"1","(2450,1375)","0","mstr_symbols","I36";
;
HDL_POWER"P3V3_STBY"
BODY_TYPE"PLUMBING"
SIZE"1B"
CDS_LIB"mstr_symbols"
VOLTAGE"3.3V";
"G\NAC"11;
END.
